(kicad_pcb
	(version 20260206)
	(generator "pcbnew")
	(generator_version "10.0")
	(general
		(thickness 1.6)
		(legacy_teardrops no)
	)
	(paper "A4")
	(title_block
		(title "v1-chassis-manager — T6M_CM_d_v01_1031_1645.brd")
		(comment 1 "Open CloudServer (Microsoft) / footprints 1766-1775 of 2512")
	)
	(layers
		(0 "F.Cu" signal "TOP")
		(4 "In1.Cu" signal "GND1")
		(6 "In2.Cu" signal "IN1")
		(8 "In3.Cu" signal "VCC1")
		(10 "In4.Cu" signal "VCC2")
		(12 "In5.Cu" signal "GND2")
		(14 "In6.Cu" signal "IN2")
		(16 "In7.Cu" signal "IN3")
		(18 "In8.Cu" signal "GND3")
		(2 "B.Cu" signal "BOTTOM")
		(9 "F.Adhes" user "F.Adhesive")
		(11 "B.Adhes" user "B.Adhesive")
		(13 "F.Paste" user "Package Geometry/Pastemask Top")
		(15 "B.Paste" user "Package Geometry/Pastemask Bottom")
		(5 "F.SilkS" user "Ref Des/Silkscreen Top")
		(7 "B.SilkS" user "Ref Des/Silkscreen Bottom")
		(1 "F.Mask" user "Board Geometry/Soldermask Top")
		(3 "B.Mask" user "Board Geometry/Soldermask Bottom")
		(17 "Dwgs.User" user "User.Drawings")
		(19 "Cmts.User" user "User.Comments")
		(21 "Eco1.User" user "User.Eco1")
		(23 "Eco2.User" user "User.Eco2")
		(25 "Edge.Cuts" user "Board Geometry/Outline")
		(27 "Margin" user)
		(31 "F.CrtYd" user "Package Geometry/Place Bound Top")
		(29 "B.CrtYd" user "Package Geometry/Place Bound Bottom")
		(35 "F.Fab" user "Ref Des/Assembly Top")
		(33 "B.Fab" user "Ref Des/Assembly Bottom")
	)
	(footprint ""
		(layer "B.Cu")
		(at 70.736968 -62.910212)
		(property "Reference" "C116"
			(at 1.576832 1.638808 0)
			(unlocked yes)
			(layer "B.SilkS")
			(effects
				(font
					(size 0.7874 0.5842)
					(thickness 0.1524)
				)
				(justify left mirror)
			)
		)
		(property "Value" ""
			(at 0 0 0)
			(layer "B.Fab")
			(effects
				(font
					(size 1.27 1.27)
				)
				(justify mirror)
			)
		)
		(duplicate_pad_numbers_are_jumpers no)
		(fp_line
			(start -0.7874 -0.4064)
			(end -0.7874 0.4064)
			(stroke
				(width 0.1524)
				(type default)
			)
			(layer "B.SilkS")
		)
		(fp_line
			(start -0.7874 0.4064)
			(end 0.7874 0.4064)
			(stroke
				(width 0.1524)
				(type default)
			)
			(layer "B.SilkS")
		)
		(fp_line
			(start 0 0.381)
			(end 0 -0.381)
			(stroke
				(width 0.1524)
				(type default)
			)
			(layer "B.SilkS")
		)
		(fp_line
			(start 0.7874 -0.4064)
			(end -0.7874 -0.4064)
			(stroke
				(width 0.1524)
				(type default)
			)
			(layer "B.SilkS")
		)
		(fp_line
			(start 0.7874 0.4064)
			(end 0.7874 -0.4064)
			(stroke
				(width 0.1524)
				(type default)
			)
			(layer "B.SilkS")
		)
		(fp_poly
			(pts
				(xy 0.5334 0.254) (xy 0.635 0.254) (xy 0.635 0.2286) (xy 0.635 -0.254) (xy 0.5334 -0.254) (xy 0.5334 -0.2794)
				(xy -0.5334 -0.2794) (xy -0.5334 -0.254) (xy -0.635 -0.254) (xy -0.635 0.254) (xy -0.5334 0.254)
				(xy -0.5334 0.2794) (xy 0.508 0.2794) (xy 0.5334 0.2794)
			)
			(stroke
				(width 0)
				(type default)
			)
			(fill no)
			(layer "B.CrtYd")
		)
		(pad "1" smd rect
			(at -0.40005 0 180)
			(size 0.4572 0.508)
			(layers "B.Cu" "B.Mask" "B.Paste")
			(net "PV_VDDR_NODE1")
		)
		(pad "2" smd rect
			(at 0.40005 0 180)
			(size 0.4572 0.508)
			(layers "B.Cu" "B.Mask" "B.Paste")
			(net "GND")
		)
	)
	(footprint ""
		(layer "B.Cu")
		(at 94.211394 -186.806586 180)
		(property "Reference" "R915"
			(at -1.315466 5.954522 0)
			(unlocked yes)
			(layer "B.SilkS")
			(effects
				(font
					(size 0.7874 0.5842)
					(thickness 0.1524)
				)
				(justify left mirror)
			)
		)
		(property "Value" ""
			(at 0 0 0)
			(layer "B.Fab")
			(effects
				(font
					(size 1.27 1.27)
				)
				(justify mirror)
			)
		)
		(duplicate_pad_numbers_are_jumpers no)
		(fp_line
			(start 0.7874 0.4064)
			(end 0.7874 -0.4064)
			(stroke
				(width 0.1524)
				(type default)
			)
			(layer "B.SilkS")
		)
		(fp_line
			(start 0.7874 -0.4064)
			(end -0.7874 -0.4064)
			(stroke
				(width 0.1524)
				(type default)
			)
			(layer "B.SilkS")
		)
		(fp_line
			(start -0.7874 0.4064)
			(end 0.7874 0.4064)
			(stroke
				(width 0.1524)
				(type default)
			)
			(layer "B.SilkS")
		)
		(fp_line
			(start -0.7874 -0.4064)
			(end -0.7874 0.4064)
			(stroke
				(width 0.1524)
				(type default)
			)
			(layer "B.SilkS")
		)
		(fp_poly
			(pts
				(xy 0.508 0.2794) (xy 0.508 0.2286) (xy 0.635 0.2286) (xy 0.635 -0.254) (xy 0.5334 -0.254) (xy 0.5334 -0.2794)
				(xy -0.5334 -0.2794) (xy -0.5334 -0.254) (xy -0.635 -0.254) (xy -0.635 0.254) (xy -0.5334 0.254)
				(xy -0.5334 0.2794)
			)
			(stroke
				(width 0)
				(type default)
			)
			(fill no)
			(layer "B.CrtYd")
		)
		(pad "1" smd rect
			(at -0.40005 0)
			(size 0.4572 0.508)
			(layers "B.Cu" "B.Mask" "B.Paste")
			(net "UART_T5_NODE2_RXD")
		)
		(pad "2" smd rect
			(at 0.40005 0)
			(size 0.4572 0.508)
			(layers "B.Cu" "B.Mask" "B.Paste")
			(net "UART_T5_NODE2_RXD_R")
		)
	)
	(footprint ""
		(layer "B.Cu")
		(at 129.895092 -172.466508)
		(property "Reference" "R976"
			(at 5.254498 -0.829056 0)
			(unlocked yes)
			(layer "B.SilkS")
			(effects
				(font
					(size 0.7874 0.5842)
					(thickness 0.1524)
				)
				(justify left mirror)
			)
		)
		(property "Value" ""
			(at 0 0 0)
			(layer "B.Fab")
			(effects
				(font
					(size 1.27 1.27)
				)
				(justify mirror)
			)
		)
		(duplicate_pad_numbers_are_jumpers no)
		(fp_line
			(start -0.7874 -0.4064)
			(end -0.7874 0.4064)
			(stroke
				(width 0.1524)
				(type default)
			)
			(layer "B.SilkS")
		)
		(fp_line
			(start -0.7874 0.4064)
			(end 0.7874 0.4064)
			(stroke
				(width 0.1524)
				(type default)
			)
			(layer "B.SilkS")
		)
		(fp_line
			(start 0.7874 -0.4064)
			(end -0.7874 -0.4064)
			(stroke
				(width 0.1524)
				(type default)
			)
			(layer "B.SilkS")
		)
		(fp_line
			(start 0.7874 0.4064)
			(end 0.7874 -0.4064)
			(stroke
				(width 0.1524)
				(type default)
			)
			(layer "B.SilkS")
		)
		(fp_poly
			(pts
				(xy 0.508 0.2794) (xy 0.508 0.2286) (xy 0.635 0.2286) (xy 0.635 -0.254) (xy 0.5334 -0.254) (xy 0.5334 -0.2794)
				(xy -0.5334 -0.2794) (xy -0.5334 -0.254) (xy -0.635 -0.254) (xy -0.635 0.254) (xy -0.5334 0.254)
				(xy -0.5334 0.2794)
			)
			(stroke
				(width 0)
				(type default)
			)
			(fill no)
			(layer "B.CrtYd")
		)
		(pad "1" smd rect
			(at -0.40005 0 180)
			(size 0.4572 0.508)
			(layers "B.Cu" "B.Mask" "B.Paste")
			(net "UART_T7_NODE4_TXD")
		)
		(pad "2" smd rect
			(at 0.40005 0 180)
			(size 0.4572 0.508)
			(layers "B.Cu" "B.Mask" "B.Paste")
			(net "UART_T7_NODE4_TXD_R")
		)
	)
	(footprint ""
		(layer "B.Cu")
		(at 56.86298 -63.885826 180)
		(property "Reference" "R29"
			(at 14.74978 -29.546296 0)
			(unlocked yes)
			(layer "B.SilkS")
			(effects
				(font
					(size 0.7874 0.5842)
					(thickness 0.1524)
				)
				(justify left mirror)
			)
		)
		(property "Value" ""
			(at 0 0 0)
			(layer "B.Fab")
			(effects
				(font
					(size 1.27 1.27)
				)
				(justify mirror)
			)
		)
		(duplicate_pad_numbers_are_jumpers no)
		(fp_line
			(start 0.7874 0.4064)
			(end 0.7874 -0.4064)
			(stroke
				(width 0.1524)
				(type default)
			)
			(layer "B.SilkS")
		)
		(fp_line
			(start 0.7874 -0.4064)
			(end -0.7874 -0.4064)
			(stroke
				(width 0.1524)
				(type default)
			)
			(layer "B.SilkS")
		)
		(fp_line
			(start -0.7874 0.4064)
			(end 0.7874 0.4064)
			(stroke
				(width 0.1524)
				(type default)
			)
			(layer "B.SilkS")
		)
		(fp_line
			(start -0.7874 -0.4064)
			(end -0.7874 0.4064)
			(stroke
				(width 0.1524)
				(type default)
			)
			(layer "B.SilkS")
		)
		(fp_poly
			(pts
				(xy 0.508 0.2794) (xy 0.508 0.2286) (xy 0.635 0.2286) (xy 0.635 -0.254) (xy 0.5334 -0.254) (xy 0.5334 -0.2794)
				(xy -0.5334 -0.2794) (xy -0.5334 -0.254) (xy -0.635 -0.254) (xy -0.635 0.254) (xy -0.5334 0.254)
				(xy -0.5334 0.2794)
			)
			(stroke
				(width 0)
				(type default)
			)
			(fill no)
			(layer "B.CrtYd")
		)
		(pad "1" smd rect
			(at -0.40005 0)
			(size 0.4572 0.508)
			(layers "B.Cu" "B.Mask" "B.Paste")
			(net "M_DDR3_NODE1_DQPU")
		)
		(pad "2" smd rect
			(at 0.40005 0)
			(size 0.4572 0.508)
			(layers "B.Cu" "B.Mask" "B.Paste")
			(net "GND")
		)
	)
	(footprint ""
		(layer "B.Cu")
		(at 167.624252 -97.04959 90)
		(property "Reference" "C370"
			(at -2.14376 -1.108964 270)
			(unlocked yes)
			(layer "B.SilkS")
			(effects
				(font
					(size 0.7874 0.5842)
					(thickness 0.1524)
				)
				(justify left mirror)
			)
		)
		(property "Value" ""
			(at 0 0 90)
			(layer "B.Fab")
			(effects
				(font
					(size 1.27 1.27)
				)
				(justify mirror)
			)
		)
		(duplicate_pad_numbers_are_jumpers no)
		(fp_line
			(start 0.7874 -0.4064)
			(end -0.7874 -0.4064)
			(stroke
				(width 0.1524)
				(type default)
			)
			(layer "B.SilkS")
		)
		(fp_line
			(start -0.7874 -0.4064)
			(end -0.7874 0.4064)
			(stroke
				(width 0.1524)
				(type default)
			)
			(layer "B.SilkS")
		)
		(fp_line
			(start 0 0.381)
			(end 0 -0.381)
			(stroke
				(width 0.1524)
				(type default)
			)
			(layer "B.SilkS")
		)
		(fp_line
			(start 0.7874 0.4064)
			(end 0.7874 -0.4064)
			(stroke
				(width 0.1524)
				(type default)
			)
			(layer "B.SilkS")
		)
		(fp_line
			(start -0.7874 0.4064)
			(end 0.7874 0.4064)
			(stroke
				(width 0.1524)
				(type default)
			)
			(layer "B.SilkS")
		)
		(fp_poly
			(pts
				(xy 0.5334 0.254) (xy 0.635 0.254) (xy 0.635 0.2286) (xy 0.635 -0.254) (xy 0.5334 -0.254) (xy 0.5334 -0.2794)
				(xy -0.5334 -0.2794) (xy -0.5334 -0.254) (xy -0.635 -0.254) (xy -0.635 0.254) (xy -0.5334 0.254)
				(xy -0.5334 0.2794) (xy 0.508 0.2794) (xy 0.5334 0.2794)
			)
			(stroke
				(width 0)
				(type default)
			)
			(fill no)
			(layer "B.CrtYd")
		)
		(pad "1" smd rect
			(at -0.40005 0 270)
			(size 0.4572 0.508)
			(layers "B.Cu" "B.Mask" "B.Paste")
			(net "P1V05_NODE1")
		)
		(pad "2" smd rect
			(at 0.40005 0 270)
			(size 0.4572 0.508)
			(layers "B.Cu" "B.Mask" "B.Paste")
			(net "GND")
		)
	)
	(footprint ""
		(layer "B.Cu")
		(at 128.701546 -34.972244)
		(property "Reference" "R1208"
			(at 1.320038 9.040368 0)
			(unlocked yes)
			(layer "B.SilkS")
			(effects
				(font
					(size 0.7874 0.5842)
					(thickness 0.1524)
				)
				(justify left mirror)
			)
		)
		(property "Value" ""
			(at 0 0 0)
			(layer "B.Fab")
			(effects
				(font
					(size 1.27 1.27)
				)
				(justify mirror)
			)
		)
		(duplicate_pad_numbers_are_jumpers no)
		(fp_line
			(start -0.7874 -0.406146)
			(end -0.7874 0.406146)
			(stroke
				(width 0.1524)
				(type default)
			)
			(layer "B.SilkS")
		)
		(fp_line
			(start -0.7874 0.406146)
			(end 0.7874 0.406146)
			(stroke
				(width 0.1524)
				(type default)
			)
			(layer "B.SilkS")
		)
		(fp_line
			(start 0.7874 -0.406146)
			(end -0.7874 -0.406146)
			(stroke
				(width 0.1524)
				(type default)
			)
			(layer "B.SilkS")
		)
		(fp_line
			(start 0.7874 0.406146)
			(end 0.7874 -0.406146)
			(stroke
				(width 0.1524)
				(type default)
			)
			(layer "B.SilkS")
		)
		(fp_poly
			(pts
				(xy 0.508 0.2794) (xy 0.508 0.2286) (xy 0.635 0.2286) (xy 0.635 -0.254) (xy 0.5334 -0.254) (xy 0.5334 -0.2794)
				(xy -0.5334 -0.2794) (xy -0.5334 -0.254) (xy -0.635 -0.254) (xy -0.635 0.254) (xy -0.5334 0.254)
				(xy -0.5334 0.2794)
			)
			(stroke
				(width 0)
				(type default)
			)
			(fill no)
			(layer "B.CrtYd")
		)
		(pad "1" smd rect
			(at -0.40005 0 180)
			(size 0.4572 0.508)
			(layers "B.Cu" "B.Mask" "B.Paste")
			(net "SIO_JTAG_CPLD3_TMS_R")
		)
		(pad "2" smd rect
			(at 0.40005 0 180)
			(size 0.4572 0.508)
			(layers "B.Cu" "B.Mask" "B.Paste")
			(net "SIO_JTAG_CPLD3_TMS")
		)
	)
	(footprint ""
		(layer "B.Cu")
		(at 98.020632 -181.672992)
		(property "Reference" "R755"
			(at 1.361948 -1.008634 0)
			(unlocked yes)
			(layer "B.SilkS")
			(effects
				(font
					(size 0.7874 0.5842)
					(thickness 0.1524)
				)
				(justify left mirror)
			)
		)
		(property "Value" ""
			(at 0 0 0)
			(layer "B.Fab")
			(effects
				(font
					(size 1.27 1.27)
				)
				(justify mirror)
			)
		)
		(duplicate_pad_numbers_are_jumpers no)
		(fp_line
			(start -0.7874 -0.4064)
			(end -0.7874 0.4064)
			(stroke
				(width 0.1524)
				(type default)
			)
			(layer "B.SilkS")
		)
		(fp_line
			(start -0.7874 0.4064)
			(end 0.7874 0.4064)
			(stroke
				(width 0.1524)
				(type default)
			)
			(layer "B.SilkS")
		)
		(fp_line
			(start 0.7874 -0.4064)
			(end -0.7874 -0.4064)
			(stroke
				(width 0.1524)
				(type default)
			)
			(layer "B.SilkS")
		)
		(fp_line
			(start 0.7874 0.4064)
			(end 0.7874 -0.4064)
			(stroke
				(width 0.1524)
				(type default)
			)
			(layer "B.SilkS")
		)
		(fp_poly
			(pts
				(xy 0.508 0.2794) (xy 0.508 0.2286) (xy 0.635 0.2286) (xy 0.635 -0.254) (xy 0.5334 -0.254) (xy 0.5334 -0.2794)
				(xy -0.5334 -0.2794) (xy -0.5334 -0.254) (xy -0.635 -0.254) (xy -0.635 0.254) (xy -0.5334 0.254)
				(xy -0.5334 0.2794)
			)
			(stroke
				(width 0)
				(type default)
			)
			(fill no)
			(layer "B.CrtYd")
		)
		(pad "1" smd rect
			(at -0.40005 0 180)
			(size 0.4572 0.508)
			(layers "B.Cu" "B.Mask" "B.Paste")
			(net "CPLD_WDT2")
		)
		(pad "2" smd rect
			(at 0.40005 0 180)
			(size 0.4572 0.508)
			(layers "B.Cu" "B.Mask" "B.Paste")
			(net "PCA_CPLD_WDT2")
		)
	)
	(footprint ""
		(layer "B.Cu")
		(at 126.635002 -116.571014 90)
		(property "Reference" "R6"
			(at -0.671576 -1.116076 270)
			(unlocked yes)
			(layer "B.SilkS")
			(effects
				(font
					(size 0.7874 0.5842)
					(thickness 0.1524)
				)
				(justify left mirror)
			)
		)
		(property "Value" ""
			(at 0 0 90)
			(layer "B.Fab")
			(effects
				(font
					(size 1.27 1.27)
				)
				(justify mirror)
			)
		)
		(duplicate_pad_numbers_are_jumpers no)
		(fp_line
			(start 0.7874 -0.4064)
			(end -0.7874 -0.4064)
			(stroke
				(width 0.1524)
				(type default)
			)
			(layer "B.SilkS")
		)
		(fp_line
			(start -0.7874 -0.4064)
			(end -0.7874 0.4064)
			(stroke
				(width 0.1524)
				(type default)
			)
			(layer "B.SilkS")
		)
		(fp_line
			(start 0.7874 0.4064)
			(end 0.7874 -0.4064)
			(stroke
				(width 0.1524)
				(type default)
			)
			(layer "B.SilkS")
		)
		(fp_line
			(start -0.7874 0.4064)
			(end 0.7874 0.4064)
			(stroke
				(width 0.1524)
				(type default)
			)
			(layer "B.SilkS")
		)
		(fp_poly
			(pts
				(xy 0.508 0.2794) (xy 0.508 0.2286) (xy 0.635 0.2286) (xy 0.635 -0.254) (xy 0.5334 -0.254) (xy 0.5334 -0.2794)
				(xy -0.5334 -0.2794) (xy -0.5334 -0.254) (xy -0.635 -0.254) (xy -0.635 0.254) (xy -0.5334 0.254)
				(xy -0.5334 0.2794)
			)
			(stroke
				(width 0)
				(type default)
			)
			(fill no)
			(layer "B.CrtYd")
		)
		(pad "1" smd rect
			(at -0.40005 0 270)
			(size 0.4572 0.508)
			(layers "B.Cu" "B.Mask" "B.Paste")
			(net "P3V3_CLK_NODE1")
		)
		(pad "2" smd rect
			(at 0.40005 0 270)
			(size 0.4572 0.508)
			(layers "B.Cu" "B.Mask" "B.Paste")
			(net "CPU_STP_NODE1")
		)
	)
	(footprint ""
		(layer "B.Cu")
		(at 40.376602 -157.716982)
		(property "Reference" "C404"
			(at -6.504178 -9.453372 0)
			(unlocked yes)
			(layer "B.SilkS")
			(effects
				(font
					(size 0.7874 0.5842)
					(thickness 0.1524)
				)
				(justify left mirror)
			)
		)
		(property "Value" ""
			(at 0 0 0)
			(layer "B.Fab")
			(effects
				(font
					(size 1.27 1.27)
				)
				(justify mirror)
			)
		)
		(duplicate_pad_numbers_are_jumpers no)
		(fp_line
			(start -0.7874 -0.4064)
			(end -0.7874 0.4064)
			(stroke
				(width 0.1524)
				(type default)
			)
			(layer "B.SilkS")
		)
		(fp_line
			(start -0.7874 0.4064)
			(end 0.7874 0.4064)
			(stroke
				(width 0.1524)
				(type default)
			)
			(layer "B.SilkS")
		)
		(fp_line
			(start 0 0.381)
			(end 0 -0.381)
			(stroke
				(width 0.1524)
				(type default)
			)
			(layer "B.SilkS")
		)
		(fp_line
			(start 0.7874 -0.4064)
			(end -0.7874 -0.4064)
			(stroke
				(width 0.1524)
				(type default)
			)
			(layer "B.SilkS")
		)
		(fp_line
			(start 0.7874 0.4064)
			(end 0.7874 -0.4064)
			(stroke
				(width 0.1524)
				(type default)
			)
			(layer "B.SilkS")
		)
		(fp_poly
			(pts
				(xy 0.5334 0.254) (xy 0.635 0.254) (xy 0.635 0.2286) (xy 0.635 -0.254) (xy 0.5334 -0.254) (xy 0.5334 -0.2794)
				(xy -0.5334 -0.2794) (xy -0.5334 -0.254) (xy -0.635 -0.254) (xy -0.635 0.254) (xy -0.5334 0.254)
				(xy -0.5334 0.2794) (xy 0.508 0.2794) (xy 0.5334 0.2794)
			)
			(stroke
				(width 0)
				(type default)
			)
			(fill no)
			(layer "B.CrtYd")
		)
		(pad "1" smd rect
			(at -0.40005 0 180)
			(size 0.4572 0.508)
			(layers "B.Cu" "B.Mask" "B.Paste")
			(net "P1V9_LAN1")
		)
		(pad "2" smd rect
			(at 0.40005 0 180)
			(size 0.4572 0.508)
			(layers "B.Cu" "B.Mask" "B.Paste")
			(net "GND")
		)
	)
	(footprint ""
		(layer "B.Cu")
		(at 140.760196 -62.88913)
		(property "Reference" "C340"
			(at -4.916424 0.066294 0)
			(unlocked yes)
			(layer "B.SilkS")
			(effects
				(font
					(size 0.7874 0.5842)
					(thickness 0.1524)
				)
				(justify left mirror)
			)
		)
		(property "Value" ""
			(at 0 0 0)
			(layer "B.Fab")
			(effects
				(font
					(size 1.27 1.27)
				)
				(justify mirror)
			)
		)
		(duplicate_pad_numbers_are_jumpers no)
		(fp_line
			(start -0.7874 -0.4064)
			(end -0.7874 0.4064)
			(stroke
				(width 0.1524)
				(type default)
			)
			(layer "B.SilkS")
		)
		(fp_line
			(start -0.7874 0.4064)
			(end 0.7874 0.4064)
			(stroke
				(width 0.1524)
				(type default)
			)
			(layer "B.SilkS")
		)
		(fp_line
			(start 0 0.381)
			(end 0 -0.381)
			(stroke
				(width 0.1524)
				(type default)
			)
			(layer "B.SilkS")
		)
		(fp_line
			(start 0.7874 -0.4064)
			(end -0.7874 -0.4064)
			(stroke
				(width 0.1524)
				(type default)
			)
			(layer "B.SilkS")
		)
		(fp_line
			(start 0.7874 0.4064)
			(end 0.7874 -0.4064)
			(stroke
				(width 0.1524)
				(type default)
			)
			(layer "B.SilkS")
		)
		(fp_poly
			(pts
				(xy 0.5334 0.254) (xy 0.635 0.254) (xy 0.635 0.2286) (xy 0.635 -0.254) (xy 0.5334 -0.254) (xy 0.5334 -0.2794)
				(xy -0.5334 -0.2794) (xy -0.5334 -0.254) (xy -0.635 -0.254) (xy -0.635 0.254) (xy -0.5334 0.254)
				(xy -0.5334 0.2794) (xy 0.508 0.2794) (xy 0.5334 0.2794)
			)
			(stroke
				(width 0)
				(type default)
			)
			(fill no)
			(layer "B.CrtYd")
		)
		(pad "1" smd rect
			(at -0.40005 0 180)
			(size 0.4572 0.508)
			(layers "B.Cu" "B.Mask" "B.Paste")
			(net "P1V0_SATA")
		)
		(pad "2" smd rect
			(at 0.40005 0 180)
			(size 0.4572 0.508)
			(layers "B.Cu" "B.Mask" "B.Paste")
			(net "GND")
		)
	)
)
